# T6G (Grand Teton) — schematic netlist excerpt (pin names and nets, part order shuffled) for the footprints in the layout excerpt that follows; sources: Cadence DE-HDL packaged netlist, KiCad conversion of 04192023_DAF0TMB3IC0_F0TG_MB_C_brd_V02_OCP.brd

C484  Q_CAP  4.7UF 6.3V 20% X6S  pkg 0402  page 356 : A = P0V9_CPU1_RT_2D ; B = GND
C313  Q_CAP  0.1UF 10V 10% X7S  pkg C0201  page 334 : A = P0V9_CPU1_RT1_2A_2D ; B = GND
C2222  Q_CAP  22UF 4V 20% X6S  pkg C0402  page 69 : A = PVDDCR_CPU1_P0 ; B = GND

(kicad_pcb
	(version 20260206)
	(generator "pcbnew")
	(generator_version "10.0")
	(general
		(thickness 1.6)
		(legacy_teardrops no)
	)
	(paper "A4")
	(title_block
		(title "04192023_DAF0TMB3IC0_F0TG_MB_C_brd_V02_OCP.brd")
		(comment 1 "Grand Teton / footprints 6086-6088 of 8354")
	)
	(layers
		(0 "F.Cu" signal "TOP")
		(4 "In1.Cu" signal "GND")
		(6 "In2.Cu" signal "IN1")
		(8 "In3.Cu" signal "GND1")
		(10 "In4.Cu" signal "IN2")
		(12 "In5.Cu" signal "GND2")
		(14 "In6.Cu" signal "IN3")
		(16 "In7.Cu" signal "GND3")
		(18 "In8.Cu" signal "VCC")
		(20 "In9.Cu" signal "VCC1")
		(22 "In10.Cu" signal "GND4")
		(24 "In11.Cu" signal "IN4")
		(26 "In12.Cu" signal "GND5")
		(28 "In13.Cu" signal "IN5")
		(30 "In14.Cu" signal "GND6")
		(32 "In15.Cu" signal "IN6")
		(34 "In16.Cu" signal "GND7")
		(2 "B.Cu" signal "BOTTOM")
		(9 "F.Adhes" user "F.Adhesive")
		(11 "B.Adhes" user "B.Adhesive")
		(13 "F.Paste" user "Package Geometry/Pastemask Top")
		(15 "B.Paste" user "Package Geometry/Pastemask Bottom")
		(5 "F.SilkS" user "Ref Des/Silkscreen Top")
		(7 "B.SilkS" user "Ref Des/Silkscreen Bottom")
		(1 "F.Mask" user "Board Geometry/Soldermask Top")
		(3 "B.Mask" user "Board Geometry/Soldermask Bottom")
		(17 "Dwgs.User" user "User.Drawings")
		(19 "Cmts.User" user "User.Comments")
		(21 "Eco1.User" user "User.Eco1")
		(23 "Eco2.User" user "User.Eco2")
		(25 "Edge.Cuts" user "Board Geometry/Outline")
		(27 "Margin" user)
		(31 "F.CrtYd" user "Package Geometry/Place Bound Top")
		(29 "B.CrtYd" user "Package Geometry/Place Bound Bottom")
		(35 "F.Fab" user "Ref Des/Assembly Top")
		(33 "B.Fab" user "Ref Des/Assembly Bottom")
	)
	(footprint ""
		(layer "B.Cu")
		(at 84.84616 -388.011162 -90)
		(property "Reference" "C313"
			(at 0 0 90)
			(layer "B.SilkS")
			(hide yes)
			(effects
				(font
					(size 1.27 1.27)
				)
				(justify mirror)
			)
		)
		(property "Value" ""
			(at 0 0 90)
			(layer "B.Fab")
			(effects
				(font
					(size 1.27 1.27)
				)
				(justify mirror)
			)
		)
		(duplicate_pad_numbers_are_jumpers no)
		(fp_line
			(start -0.299974 0.150114)
			(end 0.299974 0.150114)
			(stroke
				(width 0.1)
				(type default)
			)
			(layer "B.Fab")
		)
		(fp_line
			(start 0.299974 0.150114)
			(end 0.299974 -0.150114)
			(stroke
				(width 0.1)
				(type default)
			)
			(layer "B.Fab")
		)
		(fp_line
			(start -0.299974 -0.150114)
			(end -0.299974 0.150114)
			(stroke
				(width 0.1)
				(type default)
			)
			(layer "B.Fab")
		)
		(fp_line
			(start 0.299974 -0.150114)
			(end -0.299974 -0.150114)
			(stroke
				(width 0.1)
				(type default)
			)
			(layer "B.Fab")
		)
		(pad "1" smd rect
			(at 0.2667 0 90)
			(size 0.3048 0.381)
			(layers "B.Cu" "B.Mask" "B.Paste")
			(net "P0V9_CPU1_RT1_2A_2D")
		)
		(pad "2" smd rect
			(at -0.2667 0 90)
			(size 0.3048 0.381)
			(layers "B.Cu" "B.Mask" "B.Paste")
			(net "GND")
		)
	)
	(footprint ""
		(layer "B.Cu")
		(at 366.217454 -268.41831)
		(property "Reference" "C2222"
			(at 0 0 0)
			(layer "B.SilkS")
			(hide yes)
			(effects
				(font
					(size 1.27 1.27)
				)
				(justify mirror)
			)
		)
		(property "Value" ""
			(at 0 0 0)
			(layer "B.Fab")
			(effects
				(font
					(size 1.27 1.27)
				)
				(justify mirror)
			)
		)
		(duplicate_pad_numbers_are_jumpers no)
		(fp_line
			(start -0.7874 -0.4064)
			(end -0.7874 0.4064)
			(stroke
				(width 0.1524)
				(type default)
			)
			(layer "B.SilkS")
		)
		(fp_line
			(start -0.7874 0.4064)
			(end 0.7874 0.4064)
			(stroke
				(width 0.1524)
				(type default)
			)
			(layer "B.SilkS")
		)
		(fp_line
			(start 0.7874 -0.4064)
			(end -0.7874 -0.4064)
			(stroke
				(width 0.1524)
				(type default)
			)
			(layer "B.SilkS")
		)
		(fp_line
			(start 0.7874 0.4064)
			(end 0.7874 -0.4064)
			(stroke
				(width 0.1524)
				(type default)
			)
			(layer "B.SilkS")
		)
		(fp_line
			(start -0.67945 -0.3048)
			(end -0.67945 0.3048)
			(stroke
				(width 0.1)
				(type default)
			)
			(layer "B.Fab")
		)
		(fp_line
			(start -0.67945 0.3048)
			(end -0.120396 0.3048)
			(stroke
				(width 0.1)
				(type default)
			)
			(layer "B.Fab")
		)
		(fp_line
			(start -0.12065 -0.3048)
			(end -0.67945 -0.3048)
			(stroke
				(width 0.1)
				(type default)
			)
			(layer "B.Fab")
		)
		(fp_line
			(start -0.12065 -0.2794)
			(end -0.12065 -0.3048)
			(stroke
				(width 0.1)
				(type default)
			)
			(layer "B.Fab")
		)
		(fp_line
			(start -0.120396 0.2794)
			(end 0.12065 0.2794)
			(stroke
				(width 0.1)
				(type default)
			)
			(layer "B.Fab")
		)
		(fp_line
			(start -0.120396 0.3048)
			(end -0.120396 0.2794)
			(stroke
				(width 0.1)
				(type default)
			)
			(layer "B.Fab")
		)
		(fp_line
			(start 0.12065 -0.305054)
			(end 0.12065 -0.2794)
			(stroke
				(width 0.1)
				(type default)
			)
			(layer "B.Fab")
		)
		(fp_line
			(start 0.12065 -0.2794)
			(end -0.12065 -0.2794)
			(stroke
				(width 0.1)
				(type default)
			)
			(layer "B.Fab")
		)
		(fp_line
			(start 0.12065 0.2794)
			(end 0.12065 0.3048)
			(stroke
				(width 0.1)
				(type default)
			)
			(layer "B.Fab")
		)
		(fp_line
			(start 0.12065 0.3048)
			(end 0.67945 0.3048)
			(stroke
				(width 0.1)
				(type default)
			)
			(layer "B.Fab")
		)
		(fp_line
			(start 0.67945 -0.305054)
			(end 0.12065 -0.305054)
			(stroke
				(width 0.1)
				(type default)
			)
			(layer "B.Fab")
		)
		(fp_line
			(start 0.67945 0.3048)
			(end 0.67945 -0.305054)
			(stroke
				(width 0.1)
				(type default)
			)
			(layer "B.Fab")
		)
		(pad "1" smd circle
			(at 0.40005 0 180)
			(size 0 0)
			(layers "B.Cu" "B.Mask" "B.Paste")
			(net "PVDDCR_CPU1_P0")
		)
		(pad "2" smd circle
			(at -0.40005 0 180)
			(size 0 0)
			(layers "B.Cu" "B.Mask" "B.Paste")
			(net "GND")
		)
	)
	(footprint ""
		(layer "B.Cu")
		(at 120.49125 -390.560052 90)
		(property "Reference" "C484"
			(at 0 0 90)
			(layer "B.SilkS")
			(hide yes)
			(effects
				(font
					(size 1.27 1.27)
				)
				(justify mirror)
			)
		)
		(property "Value" ""
			(at 0 0 90)
			(layer "B.Fab")
			(effects
				(font
					(size 1.27 1.27)
				)
				(justify mirror)
			)
		)
		(duplicate_pad_numbers_are_jumpers no)
		(fp_line
			(start 0.7874 -0.4064)
			(end -0.7874 -0.4064)
			(stroke
				(width 0.1524)
				(type default)
			)
			(layer "B.SilkS")
		)
		(fp_line
			(start -0.7874 -0.4064)
			(end -0.7874 0.4064)
			(stroke
				(width 0.1524)
				(type default)
			)
			(layer "B.SilkS")
		)
		(fp_line
			(start 0.7874 0.4064)
			(end 0.7874 -0.4064)
			(stroke
				(width 0.1524)
				(type default)
			)
			(layer "B.SilkS")
		)
		(fp_line
			(start -0.7874 0.4064)
			(end 0.7874 0.4064)
			(stroke
				(width 0.1524)
				(type default)
			)
			(layer "B.SilkS")
		)
		(fp_line
			(start 0.67945 -0.305054)
			(end 0.12065 -0.305054)
			(stroke
				(width 0.1)
				(type default)
			)
			(layer "B.Fab")
		)
		(fp_line
			(start 0.12065 -0.305054)
			(end 0.12065 -0.2794)
			(stroke
				(width 0.1)
				(type default)
			)
			(layer "B.Fab")
		)
		(fp_line
			(start -0.12065 -0.3048)
			(end -0.67945 -0.3048)
			(stroke
				(width 0.1)
				(type default)
			)
			(layer "B.Fab")
		)
		(fp_line
			(start -0.67945 -0.3048)
			(end -0.67945 0.3048)
			(stroke
				(width 0.1)
				(type default)
			)
			(layer "B.Fab")
		)
		(fp_line
			(start 0.12065 -0.2794)
			(end -0.12065 -0.2794)
			(stroke
				(width 0.1)
				(type default)
			)
			(layer "B.Fab")
		)
		(fp_line
			(start -0.12065 -0.2794)
			(end -0.12065 -0.3048)
			(stroke
				(width 0.1)
				(type default)
			)
			(layer "B.Fab")
		)
		(fp_line
			(start 0.12065 0.2794)
			(end 0.12065 0.3048)
			(stroke
				(width 0.1)
				(type default)
			)
			(layer "B.Fab")
		)
		(fp_line
			(start -0.120396 0.2794)
			(end 0.12065 0.2794)
			(stroke
				(width 0.1)
				(type default)
			)
			(layer "B.Fab")
		)
		(fp_line
			(start 0.67945 0.3048)
			(end 0.67945 -0.305054)
			(stroke
				(width 0.1)
				(type default)
			)
			(layer "B.Fab")
		)
		(fp_line
			(start 0.12065 0.3048)
			(end 0.67945 0.3048)
			(stroke
				(width 0.1)
				(type default)
			)
			(layer "B.Fab")
		)
		(fp_line
			(start -0.120396 0.3048)
			(end -0.120396 0.2794)
			(stroke
				(width 0.1)
				(type default)
			)
			(layer "B.Fab")
		)
		(fp_line
			(start -0.67945 0.3048)
			(end -0.120396 0.3048)
			(stroke
				(width 0.1)
				(type default)
			)
			(layer "B.Fab")
		)
		(pad "1" smd circle
			(at 0.40005 0 270)
			(size 0 0)
			(layers "B.Cu" "B.Mask" "B.Paste")
			(net "P0V9_CPU1_RT_2D")
		)
		(pad "2" smd circle
			(at -0.40005 0 270)
			(size 0 0)
			(layers "B.Cu" "B.Mask" "B.Paste")
			(net "GND")
		)
	)
)
